# BASEBOARD_FAB2 (Tioga Pass) — schematic netlist excerpt (pin names and nets, part order shuffled) for the footprints in the layout excerpt that follows; sources: Cadence DE-HDL packaged netlist, KiCad conversion of Wiwynn_Tioga_Pass_MB.brd

R3N13  RES  4.75K 1% CHIP  pkg 0402  page 118 : A = P3V3_STBY ; B = IRQ_LVC3_WAKE_N
C3M42  CAP_A  1.0UF 6.3V 10% X6S  pkg 0402V  page 131 : A = P1V05_PCH_STBY ; B = GND
R7P8  RES  49.9 1% CHIP  pkg 0402  page 55 : A = A_CPU1_PE3_RBIAS ; B = GND

(kicad_pcb
	(version 20260206)
	(generator "pcbnew")
	(generator_version "10.0")
	(general
		(thickness 1.6)
		(legacy_teardrops no)
	)
	(paper "A4")
	(title_block
		(title "Wiwynn_Tioga_Pass_MB.brd")
		(comment 1 "Tioga Pass / footprints 4619-4621 of 4770")
	)
	(layers
		(0 "F.Cu" signal "TOP")
		(4 "In1.Cu" signal "L2GND")
		(6 "In2.Cu" signal "L3")
		(8 "In3.Cu" signal "L4GND")
		(10 "In4.Cu" signal "L5")
		(12 "In5.Cu" signal "L6GND")
		(14 "In6.Cu" signal "L7VCC")
		(16 "In7.Cu" signal "L8VCC")
		(18 "In8.Cu" signal "L9GND")
		(20 "In9.Cu" signal "L10")
		(22 "In10.Cu" signal "L11GND")
		(24 "In11.Cu" signal "L12")
		(26 "In12.Cu" signal "L13GND")
		(2 "B.Cu" signal "BOTTOM")
		(9 "F.Adhes" user "F.Adhesive")
		(11 "B.Adhes" user "B.Adhesive")
		(13 "F.Paste" user "Package Geometry/Pastemask Top")
		(15 "B.Paste" user "Package Geometry/Pastemask Bottom")
		(5 "F.SilkS" user "Ref Des/Silkscreen Top")
		(7 "B.SilkS" user "Ref Des/Silkscreen Bottom")
		(1 "F.Mask" user "Board Geometry/Soldermask Top")
		(3 "B.Mask" user "Board Geometry/Soldermask Bottom")
		(17 "Dwgs.User" user "User.Drawings")
		(19 "Cmts.User" user "User.Comments")
		(21 "Eco1.User" user "User.Eco1")
		(23 "Eco2.User" user "User.Eco2")
		(25 "Edge.Cuts" user "Board Geometry/Outline")
		(27 "Margin" user)
		(31 "F.CrtYd" user "Package Geometry/Place Bound Top")
		(29 "B.CrtYd" user "Package Geometry/Place Bound Bottom")
		(35 "F.Fab" user "Ref Des/Assembly Top")
		(33 "B.Fab" user "Ref Des/Assembly Bottom")
	)
	(footprint ""
		(layer "B.Cu")
		(at 117.221 -78.74 -90)
		(property "Reference" "R7P8"
			(at 0 0 90)
			(layer "B.SilkS")
			(hide yes)
			(effects
				(font
					(size 1.27 1.27)
				)
				(justify mirror)
			)
		)
		(property "Value" ""
			(at 0 0 90)
			(layer "B.Fab")
			(effects
				(font
					(size 1.27 1.27)
				)
				(justify mirror)
			)
		)
		(duplicate_pad_numbers_are_jumpers no)
		(fp_poly
			(pts
				(xy 0.2794 -0.1016) (xy -0.2794 -0.1016) (xy -0.2794 0.9906) (xy 0.2794 0.9906)
			)
			(stroke
				(width 0)
				(type default)
			)
			(fill no)
			(layer "B.CrtYd")
		)
		(fp_line
			(start -0.2794 0.9906)
			(end -0.2794 -0.1016)
			(stroke
				(width 0.1)
				(type default)
			)
			(layer "B.Fab")
		)
		(fp_line
			(start 0.2794 0.9906)
			(end -0.2794 0.9906)
			(stroke
				(width 0.1)
				(type default)
			)
			(layer "B.Fab")
		)
		(fp_line
			(start -0.2794 -0.1016)
			(end 0.2794 -0.1016)
			(stroke
				(width 0.1)
				(type default)
			)
			(layer "B.Fab")
		)
		(fp_line
			(start 0.2794 -0.1016)
			(end 0.2794 0.9906)
			(stroke
				(width 0.1)
				(type default)
			)
			(layer "B.Fab")
		)
		(pad "1" smd rect
			(at 0 0 90)
			(size 0.508 0.508)
			(layers "B.Cu" "B.Mask" "B.Paste")
			(net "A_CPU1_PE3_RBIAS")
		)
		(pad "2" smd rect
			(at 0 0.889 90)
			(size 0.508 0.508)
			(layers "B.Cu" "B.Mask" "B.Paste")
			(net "GND")
		)
		(zone
			(layer "B.Cu")
			(hatch none 0.5)
			(connect_pads
				(clearance 0)
			)
			(min_thickness 0.25)
			(keepout
				(tracks not_allowed)
				(vias allowed)
				(pads allowed)
				(copperpour not_allowed)
				(footprints allowed)
			)
			(placement
				(enabled no)
				(sheetname "")
			)
			(fill
				(thermal_gap 0.5)
				(thermal_bridge_width 0.5)
				(island_removal_mode 0)
			)
			(polygon
				(pts
					(xy 116.586 -78.486) (xy 116.586 -78.994) (xy 116.967 -78.994) (xy 116.967 -78.486)
				)
			)
		)
		(zone
			(layer "B.Cu")
			(hatch none 0.5)
			(connect_pads
				(clearance 0)
			)
			(min_thickness 0.25)
			(keepout
				(tracks allowed)
				(vias not_allowed)
				(pads allowed)
				(copperpour not_allowed)
				(footprints allowed)
			)
			(placement
				(enabled no)
				(sheetname "")
			)
			(fill
				(thermal_gap 0.5)
				(thermal_bridge_width 0.5)
				(island_removal_mode 0)
			)
			(polygon
				(pts
					(xy 116.967 -78.486) (xy 116.967 -78.994) (xy 116.586 -78.994) (xy 116.586 -78.486)
				)
			)
		)
	)
	(footprint ""
		(layer "B.Cu")
		(at 372.5164 -91.567 90)
		(property "Reference" "R3N13"
			(at 0 0 90)
			(layer "B.SilkS")
			(hide yes)
			(effects
				(font
					(size 1.27 1.27)
				)
				(justify mirror)
			)
		)
		(property "Value" ""
			(at 0 0 90)
			(layer "B.Fab")
			(effects
				(font
					(size 1.27 1.27)
				)
				(justify mirror)
			)
		)
		(duplicate_pad_numbers_are_jumpers no)
		(fp_poly
			(pts
				(xy 0.2794 -0.1016) (xy -0.2794 -0.1016) (xy -0.2794 0.9906) (xy 0.2794 0.9906)
			)
			(stroke
				(width 0)
				(type default)
			)
			(fill no)
			(layer "B.CrtYd")
		)
		(fp_line
			(start 0.2794 -0.1016)
			(end 0.2794 0.9906)
			(stroke
				(width 0.1)
				(type default)
			)
			(layer "B.Fab")
		)
		(fp_line
			(start -0.2794 -0.1016)
			(end 0.2794 -0.1016)
			(stroke
				(width 0.1)
				(type default)
			)
			(layer "B.Fab")
		)
		(fp_line
			(start 0.2794 0.9906)
			(end -0.2794 0.9906)
			(stroke
				(width 0.1)
				(type default)
			)
			(layer "B.Fab")
		)
		(fp_line
			(start -0.2794 0.9906)
			(end -0.2794 -0.1016)
			(stroke
				(width 0.1)
				(type default)
			)
			(layer "B.Fab")
		)
		(pad "1" smd rect
			(at 0 0 270)
			(size 0.508 0.508)
			(layers "B.Cu" "B.Mask" "B.Paste")
			(net "P3V3_STBY")
		)
		(pad "2" smd rect
			(at 0 0.889 270)
			(size 0.508 0.508)
			(layers "B.Cu" "B.Mask" "B.Paste")
			(net "IRQ_LVC3_WAKE_N")
		)
		(zone
			(layer "B.Cu")
			(hatch none 0.5)
			(connect_pads
				(clearance 0)
			)
			(min_thickness 0.25)
			(keepout
				(tracks allowed)
				(vias not_allowed)
				(pads allowed)
				(copperpour not_allowed)
				(footprints allowed)
			)
			(placement
				(enabled no)
				(sheetname "")
			)
			(fill
				(thermal_gap 0.5)
				(thermal_bridge_width 0.5)
				(island_removal_mode 0)
			)
			(polygon
				(pts
					(xy 372.7704 -91.821) (xy 372.7704 -91.313) (xy 373.1514 -91.313) (xy 373.1514 -91.821)
				)
			)
		)
		(zone
			(layer "B.Cu")
			(hatch none 0.5)
			(connect_pads
				(clearance 0)
			)
			(min_thickness 0.25)
			(keepout
				(tracks not_allowed)
				(vias allowed)
				(pads allowed)
				(copperpour not_allowed)
				(footprints allowed)
			)
			(placement
				(enabled no)
				(sheetname "")
			)
			(fill
				(thermal_gap 0.5)
				(thermal_bridge_width 0.5)
				(island_removal_mode 0)
			)
			(polygon
				(pts
					(xy 373.1514 -91.821) (xy 373.1514 -91.313) (xy 372.7704 -91.313) (xy 372.7704 -91.821)
				)
			)
		)
	)
	(footprint ""
		(layer "B.Cu")
		(at 388.1374 -113.4999)
		(property "Reference" "C3M42"
			(at 0 0 0)
			(layer "B.SilkS")
			(hide yes)
			(effects
				(font
					(size 1.27 1.27)
				)
				(justify mirror)
			)
		)
		(property "Value" ""
			(at 0 0 0)
			(layer "B.Fab")
			(effects
				(font
					(size 1.27 1.27)
				)
				(justify mirror)
			)
		)
		(duplicate_pad_numbers_are_jumpers no)
		(fp_poly
			(pts
				(xy -0.3048 -0.1016) (xy -0.3048 0.9906) (xy 0.3048 0.9906) (xy 0.3048 -0.1016)
			)
			(stroke
				(width 0)
				(type default)
			)
			(fill no)
			(layer "B.CrtYd")
		)
		(fp_line
			(start -0.3048 -0.1016)
			(end 0.3048 -0.1016)
			(stroke
				(width 0.1)
				(type default)
			)
			(layer "B.Fab")
		)
		(fp_line
			(start -0.3048 0.9906)
			(end -0.3048 -0.1016)
			(stroke
				(width 0.1)
				(type default)
			)
			(layer "B.Fab")
		)
		(fp_line
			(start 0.3048 -0.1016)
			(end 0.3048 0.9906)
			(stroke
				(width 0.1)
				(type default)
			)
			(layer "B.Fab")
		)
		(fp_line
			(start 0.3048 0.9906)
			(end -0.3048 0.9906)
			(stroke
				(width 0.1)
				(type default)
			)
			(layer "B.Fab")
		)
		(pad "1" smd rect
			(at 0 0 180)
			(size 0.508 0.508)
			(layers "B.Cu" "B.Mask" "B.Paste")
			(net "P1V05_PCH_STBY")
		)
		(pad "2" smd rect
			(at 0 0.889 180)
			(size 0.508 0.508)
			(layers "B.Cu" "B.Mask" "B.Paste")
			(net "GND")
		)
		(zone
			(layer "B.Cu")
			(hatch none 0.5)
			(connect_pads
				(clearance 0)
			)
			(min_thickness 0.25)
			(keepout
				(tracks allowed)
				(vias not_allowed)
				(pads allowed)
				(copperpour not_allowed)
				(footprints allowed)
			)
			(placement
				(enabled no)
				(sheetname "")
			)
			(fill
				(thermal_gap 0.5)
				(thermal_bridge_width 0.5)
				(island_removal_mode 0)
			)
			(polygon
				(pts
					(xy 388.3914 -113.2459) (xy 387.8834 -113.2459) (xy 387.8834 -112.8649) (xy 388.3914 -112.8649)
				)
			)
		)
		(zone
			(layer "B.Cu")
			(hatch none 0.5)
			(connect_pads
				(clearance 0)
			)
			(min_thickness 0.25)
			(keepout
				(tracks not_allowed)
				(vias allowed)
				(pads allowed)
				(copperpour not_allowed)
				(footprints allowed)
			)
			(placement
				(enabled no)
				(sheetname "")
			)
			(fill
				(thermal_gap 0.5)
				(thermal_bridge_width 0.5)
				(island_removal_mode 0)
			)
			(polygon
				(pts
					(xy 388.3914 -112.8649) (xy 387.8834 -112.8649) (xy 387.8834 -113.2459) (xy 388.3914 -113.2459)
				)
			)
		)
	)
)
